(kicad_pcb
	(version 20241229)
	(generator "pcbnew")
	(generator_version "9.0")
	(general
		(thickness 1.61)
		(legacy_teardrops no)
	)
	(paper "A3")
	(title_block
		(title "RDIMM DDR5 Tester")
		(date "2026-05-21")
		(rev "2.2.0")
		(company "Antmicro")
		(comment 9 "footprints 22-26 of 796")
	)
	(layers
		(0 "F.Cu" signal)
		(4 "In1.Cu" power)
		(6 "In2.Cu" mixed)
		(8 "In3.Cu" power)
		(10 "In4.Cu" mixed)
		(12 "In5.Cu" power)
		(14 "In6.Cu" mixed)
		(16 "In7.Cu" power)
		(18 "In8.Cu" power)
		(20 "In9.Cu" mixed)
		(22 "In10.Cu" power)
		(2 "B.Cu" signal)
		(9 "F.Adhes" user "F.Adhesive")
		(11 "B.Adhes" user "B.Adhesive")
		(13 "F.Paste" user)
		(15 "B.Paste" user)
		(5 "F.SilkS" user "F.Silkscreen")
		(7 "B.SilkS" user "B.Silkscreen")
		(1 "F.Mask" user)
		(3 "B.Mask" user)
		(17 "Dwgs.User" user "User.Drawings")
		(19 "Cmts.User" user "User.Comments")
		(21 "Eco1.User" user "User.Eco1")
		(23 "Eco2.User" user "User.Eco2")
		(25 "Edge.Cuts" user)
		(27 "Margin" user)
		(31 "F.CrtYd" user "F.Courtyard")
		(29 "B.CrtYd" user "B.Courtyard")
		(35 "F.Fab" user)
		(33 "B.Fab" user)
	)
	(footprint "antmicro-footprints:R_0402_1005Metric"
		(layer "F.Cu")
		(at 115.75 153.65 180)
		(descr "Resistor SMD 0402")
		(tags "resistor SMD 0402")
		(property "Reference" "R84"
			(at -1.025 1.8 0)
			(layer "F.SilkS")
			(effects
				(font
					(size 0.7 0.7)
					(thickness 0.15)
				)
				(justify right bottom)
			)
		)
		(property "Value" "R_330R_0402"
			(at -1.011843 1.772047 0)
			(layer "F.Fab")
			(effects
				(font
					(size 0.7 0.7)
					(thickness 0.15)
				)
				(justify right bottom)
			)
		)
		(property "Datasheet" "https://www.bourns.com/docs/product-datasheets/cr.pdf"
			(at 0 0 180)
			(layer "F.Fab")
			(hide yes)
			(effects
				(font
					(size 1.27 1.27)
					(thickness 0.15)
				)
			)
		)
		(property "Manufacturer" "Bourns"
			(at 0 0 180)
			(unlocked yes)
			(layer "F.Fab")
			(hide yes)
			(effects
				(font
					(size 1 1)
					(thickness 0.15)
				)
			)
		)
		(property "MPN" "CR0402-FX-3300GLF"
			(at 0 0 180)
			(unlocked yes)
			(layer "F.Fab")
			(hide yes)
			(effects
				(font
					(size 1 1)
					(thickness 0.15)
				)
			)
		)
		(property "Val" "330R"
			(at 0 0 180)
			(unlocked yes)
			(layer "F.Fab")
			(hide yes)
			(effects
				(font
					(size 1 1)
					(thickness 0.15)
				)
			)
		)
		(property "License" "Apache-2.0"
			(at 0 0 180)
			(unlocked yes)
			(layer "F.Fab")
			(hide yes)
			(effects
				(font
					(size 1 1)
					(thickness 0.15)
				)
			)
		)
		(property "Author" "Antmicro"
			(at 0 0 180)
			(unlocked yes)
			(layer "F.Fab")
			(hide yes)
			(effects
				(font
					(size 1 1)
					(thickness 0.15)
				)
			)
		)
		(property "Tolerance" "1%"
			(at 0 0 180)
			(unlocked yes)
			(layer "F.Fab")
			(hide yes)
			(effects
				(font
					(size 1 1)
					(thickness 0.15)
				)
			)
		)
		(sheetname "/HDMI + SD Card/")
		(sheetfile "hdmi-sd-card.kicad_sch")
		(attr smd)
		(fp_rect
			(start -0.925 -0.47)
			(end 0.925 0.47)
			(stroke
				(width 0.05)
				(type default)
			)
			(fill no)
			(layer "F.CrtYd")
		)
		(fp_rect
			(start -0.5 -0.25)
			(end 0.5 0.25)
			(stroke
				(width 0.15)
				(type solid)
			)
			(fill no)
			(layer "F.Fab")
		)
		(fp_text user "License: Apache-2.0"
			(at -0.95 5.169 180)
			(layer "F.Fab")
			(effects
				(font
					(size 0.7 0.7)
					(thickness 0.15)
				)
				(justify left bottom)
			)
		)
		(fp_text user "${REFERENCE}"
			(at -0.95 3.168 180)
			(layer "F.Fab")
			(effects
				(font
					(size 0.7 0.7)
					(thickness 0.15)
				)
				(justify left bottom)
			)
		)
		(fp_text user "Author: Antmicro"
			(at -0.95 4.169 180)
			(layer "F.Fab")
			(effects
				(font
					(size 0.7 0.7)
					(thickness 0.15)
				)
				(justify left bottom)
			)
		)
		(pad "1" smd roundrect
			(at -0.48 0 180)
			(size 0.59 0.64)
			(layers "F.Cu" "F.Mask" "F.Paste")
			(roundrect_rratio 0.25)
			(net 635 "/FPGA banks HP/SD.CD")
			(pintype "passive")
		)
		(pad "2" smd roundrect
			(at 0.48 0 180)
			(size 0.59 0.64)
			(layers "F.Cu" "F.Mask" "F.Paste")
			(roundrect_rratio 0.25)
			(net 249 "Net-(J5-CD_SW1)")
			(pintype "passive")
		)
	)
	(footprint "antmicro-footprints:C_0402_1005Metric"
		(layer "F.Cu")
		(at 134.8135 159.984 90)
		(descr "Capacitor SMD 0402")
		(tags "capacitor SMD 0402")
		(property "Reference" "C112"
			(at -1.066 2.2865 90)
			(layer "F.SilkS")
			(effects
				(font
					(size 0.7 0.7)
					(thickness 0.15)
				)
				(justify left bottom)
			)
		)
		(property "Value" "C_100n_0402"
			(at -1.022927 2.155213 90)
			(layer "F.Fab")
			(effects
				(font
					(size 0.7 0.7)
					(thickness 0.15)
				)
				(justify left bottom)
			)
		)
		(property "Datasheet" "https://www.murata.com/products/productdetail?partno=GRM155R61H104KE14%23"
			(at 0 0 90)
			(layer "F.Fab")
			(hide yes)
			(effects
				(font
					(size 1.27 1.27)
					(thickness 0.15)
				)
			)
		)
		(property "Manufacturer" "Murata"
			(at 0 0 90)
			(unlocked yes)
			(layer "F.Fab")
			(hide yes)
			(effects
				(font
					(size 1 1)
					(thickness 0.15)
				)
			)
		)
		(property "MPN" "GRM155R61H104KE14D"
			(at 0 0 90)
			(unlocked yes)
			(layer "F.Fab")
			(hide yes)
			(effects
				(font
					(size 1 1)
					(thickness 0.15)
				)
			)
		)
		(property "Val" "100n"
			(at 0 0 90)
			(unlocked yes)
			(layer "F.Fab")
			(hide yes)
			(effects
				(font
					(size 1 1)
					(thickness 0.15)
				)
			)
		)
		(property "License" "Apache-2.0"
			(at 0 0 90)
			(unlocked yes)
			(layer "F.Fab")
			(hide yes)
			(effects
				(font
					(size 1 1)
					(thickness 0.15)
				)
			)
		)
		(property "Author" "Antmicro"
			(at 0 0 90)
			(unlocked yes)
			(layer "F.Fab")
			(hide yes)
			(effects
				(font
					(size 1 1)
					(thickness 0.15)
				)
			)
		)
		(property "Voltage" "50V"
			(at 0 0 90)
			(unlocked yes)
			(layer "F.Fab")
			(hide yes)
			(effects
				(font
					(size 1 1)
					(thickness 0.15)
				)
			)
		)
		(property "Dielectric" "X5R"
			(at 0 0 90)
			(unlocked yes)
			(layer "F.Fab")
			(hide yes)
			(effects
				(font
					(size 1 1)
					(thickness 0.15)
				)
			)
		)
		(sheetname "/Debug FTDI + VNA/")
		(sheetfile "debug-ftdi.kicad_sch")
		(attr smd)
		(fp_rect
			(start -0.925 -0.47)
			(end 0.925 0.47)
			(stroke
				(width 0.05)
				(type default)
			)
			(fill no)
			(layer "F.CrtYd")
		)
		(fp_line
			(start 0.504 -0.25)
			(end 0.504 0.248)
			(stroke
				(width 0.15)
				(type solid)
			)
			(layer "F.Fab")
		)
		(fp_line
			(start -0.494 -0.25)
			(end 0.504 -0.25)
			(stroke
				(width 0.15)
				(type solid)
			)
			(layer "F.Fab")
		)
		(fp_line
			(start 0.504 0.248)
			(end -0.494 0.248)
			(stroke
				(width 0.15)
				(type solid)
			)
			(layer "F.Fab")
		)
		(fp_line
			(start -0.494 0.248)
			(end -0.494 -0.25)
			(stroke
				(width 0.15)
				(type solid)
			)
			(layer "F.Fab")
		)
		(fp_text user "${REFERENCE}"
			(at -0.939 4.599 90)
			(layer "F.Fab")
			(effects
				(font
					(size 0.7 0.7)
					(thickness 0.15)
				)
				(justify left bottom)
			)
		)
		(fp_text user "Author: Antmicro"
			(at -0.939 3.399 90)
			(layer "F.Fab")
			(effects
				(font
					(size 0.7 0.7)
					(thickness 0.15)
				)
				(justify left bottom)
			)
		)
		(fp_text user "License: Apache-2.0"
			(at -0.939 5.799 90)
			(layer "F.Fab")
			(effects
				(font
					(size 0.7 0.7)
					(thickness 0.15)
				)
				(justify left bottom)
			)
		)
		(pad "1" smd roundrect
			(at -0.48 0 90)
			(size 0.59 0.64)
			(layers "F.Cu" "F.Mask" "F.Paste")
			(roundrect_rratio 0.25)
			(net 5 "/Debug FTDI + VNA/FTDI_VPHY")
			(pintype "passive")
		)
		(pad "2" smd roundrect
			(at 0.48 0 90)
			(size 0.59 0.64)
			(layers "F.Cu" "F.Mask" "F.Paste")
			(roundrect_rratio 0.25)
			(net 1 "GND")
			(pintype "passive")
		)
	)
	(footprint "antmicro-footprints:C_0402_1005Metric"
		(layer "F.Cu")
		(at 142.971843 155.991328 90)
		(descr "Capacitor SMD 0402")
		(tags "capacitor SMD 0402")
		(property "Reference" "C118"
			(at 0.991328 0.348157 90)
			(layer "F.SilkS")
			(effects
				(font
					(size 0.7 0.7)
					(thickness 0.15)
				)
				(justify left bottom)
			)
		)
		(property "Value" "C_100n_0402"
			(at -1.022927 2.155213 90)
			(layer "F.Fab")
			(effects
				(font
					(size 0.7 0.7)
					(thickness 0.15)
				)
				(justify left bottom)
			)
		)
		(property "Datasheet" "https://www.murata.com/products/productdetail?partno=GRM155R61H104KE14%23"
			(at 0 0 90)
			(layer "F.Fab")
			(hide yes)
			(effects
				(font
					(size 1.27 1.27)
					(thickness 0.15)
				)
			)
		)
		(property "Manufacturer" "Murata"
			(at 0 0 90)
			(unlocked yes)
			(layer "F.Fab")
			(hide yes)
			(effects
				(font
					(size 1 1)
					(thickness 0.15)
				)
			)
		)
		(property "MPN" "GRM155R61H104KE14D"
			(at 0 0 90)
			(unlocked yes)
			(layer "F.Fab")
			(hide yes)
			(effects
				(font
					(size 1 1)
					(thickness 0.15)
				)
			)
		)
		(property "Val" "100n"
			(at 0 0 90)
			(unlocked yes)
			(layer "F.Fab")
			(hide yes)
			(effects
				(font
					(size 1 1)
					(thickness 0.15)
				)
			)
		)
		(property "License" "Apache-2.0"
			(at 0 0 90)
			(unlocked yes)
			(layer "F.Fab")
			(hide yes)
			(effects
				(font
					(size 1 1)
					(thickness 0.15)
				)
			)
		)
		(property "Author" "Antmicro"
			(at 0 0 90)
			(unlocked yes)
			(layer "F.Fab")
			(hide yes)
			(effects
				(font
					(size 1 1)
					(thickness 0.15)
				)
			)
		)
		(property "Voltage" "50V"
			(at 0 0 90)
			(unlocked yes)
			(layer "F.Fab")
			(hide yes)
			(effects
				(font
					(size 1 1)
					(thickness 0.15)
				)
			)
		)
		(property "Dielectric" "X5R"
			(at 0 0 90)
			(unlocked yes)
			(layer "F.Fab")
			(hide yes)
			(effects
				(font
					(size 1 1)
					(thickness 0.15)
				)
			)
		)
		(sheetname "/Debug FTDI + VNA/")
		(sheetfile "debug-ftdi.kicad_sch")
		(attr smd)
		(fp_rect
			(start -0.925 -0.47)
			(end 0.925 0.47)
			(stroke
				(width 0.05)
				(type default)
			)
			(fill no)
			(layer "F.CrtYd")
		)
		(fp_line
			(start 0.504 -0.25)
			(end 0.504 0.248)
			(stroke
				(width 0.15)
				(type solid)
			)
			(layer "F.Fab")
		)
		(fp_line
			(start -0.494 -0.25)
			(end 0.504 -0.25)
			(stroke
				(width 0.15)
				(type solid)
			)
			(layer "F.Fab")
		)
		(fp_line
			(start 0.504 0.248)
			(end -0.494 0.248)
			(stroke
				(width 0.15)
				(type solid)
			)
			(layer "F.Fab")
		)
		(fp_line
			(start -0.494 0.248)
			(end -0.494 -0.25)
			(stroke
				(width 0.15)
				(type solid)
			)
			(layer "F.Fab")
		)
		(fp_text user "Author: Antmicro"
			(at -0.939 3.399 90)
			(layer "F.Fab")
			(effects
				(font
					(size 0.7 0.7)
					(thickness 0.15)
				)
				(justify left bottom)
			)
		)
		(fp_text user "${REFERENCE}"
			(at -0.939 4.599 90)
			(layer "F.Fab")
			(effects
				(font
					(size 0.7 0.7)
					(thickness 0.15)
				)
				(justify left bottom)
			)
		)
		(fp_text user "License: Apache-2.0"
			(at -0.939 5.799 90)
			(layer "F.Fab")
			(effects
				(font
					(size 0.7 0.7)
					(thickness 0.15)
				)
				(justify left bottom)
			)
		)
		(pad "1" smd roundrect
			(at -0.48 0 90)
			(size 0.59 0.64)
			(layers "F.Cu" "F.Mask" "F.Paste")
			(roundrect_rratio 0.25)
			(net 6 "/Debug FTDI + VNA/FTDI_3V3")
			(pintype "passive")
		)
		(pad "2" smd roundrect
			(at 0.48 0 90)
			(size 0.59 0.64)
			(layers "F.Cu" "F.Mask" "F.Paste")
			(roundrect_rratio 0.25)
			(net 1 "GND")
			(pintype "passive")
		)
	)
	(footprint "antmicro-footprints:C_0402_1005Metric"
		(layer "F.Cu")
		(at 144.051843 155.991328 90)
		(descr "Capacitor SMD 0402")
		(tags "capacitor SMD 0402")
		(property "Reference" "C125"
			(at 0.991328 0.348157 90)
			(layer "F.SilkS")
			(effects
				(font
					(size 0.7 0.7)
					(thickness 0.15)
				)
				(justify left bottom)
			)
		)
		(property "Value" "C_100n_0402"
			(at -1.022927 2.155213 90)
			(layer "F.Fab")
			(effects
				(font
					(size 0.7 0.7)
					(thickness 0.15)
				)
				(justify left bottom)
			)
		)
		(property "Datasheet" "https://www.murata.com/products/productdetail?partno=GRM155R61H104KE14%23"
			(at 0 0 90)
			(layer "F.Fab")
			(hide yes)
			(effects
				(font
					(size 1.27 1.27)
					(thickness 0.15)
				)
			)
		)
		(property "Manufacturer" "Murata"
			(at 0 0 90)
			(unlocked yes)
			(layer "F.Fab")
			(hide yes)
			(effects
				(font
					(size 1 1)
					(thickness 0.15)
				)
			)
		)
		(property "MPN" "GRM155R61H104KE14D"
			(at 0 0 90)
			(unlocked yes)
			(layer "F.Fab")
			(hide yes)
			(effects
				(font
					(size 1 1)
					(thickness 0.15)
				)
			)
		)
		(property "Val" "100n"
			(at 0 0 90)
			(unlocked yes)
			(layer "F.Fab")
			(hide yes)
			(effects
				(font
					(size 1 1)
					(thickness 0.15)
				)
			)
		)
		(property "License" "Apache-2.0"
			(at 0 0 90)
			(unlocked yes)
			(layer "F.Fab")
			(hide yes)
			(effects
				(font
					(size 1 1)
					(thickness 0.15)
				)
			)
		)
		(property "Author" "Antmicro"
			(at 0 0 90)
			(unlocked yes)
			(layer "F.Fab")
			(hide yes)
			(effects
				(font
					(size 1 1)
					(thickness 0.15)
				)
			)
		)
		(property "Voltage" "50V"
			(at 0 0 90)
			(unlocked yes)
			(layer "F.Fab")
			(hide yes)
			(effects
				(font
					(size 1 1)
					(thickness 0.15)
				)
			)
		)
		(property "Dielectric" "X5R"
			(at 0 0 90)
			(unlocked yes)
			(layer "F.Fab")
			(hide yes)
			(effects
				(font
					(size 1 1)
					(thickness 0.15)
				)
			)
		)
		(sheetname "/Debug FTDI + VNA/")
		(sheetfile "debug-ftdi.kicad_sch")
		(attr smd)
		(fp_rect
			(start -0.925 -0.47)
			(end 0.925 0.47)
			(stroke
				(width 0.05)
				(type default)
			)
			(fill no)
			(layer "F.CrtYd")
		)
		(fp_line
			(start 0.504 -0.25)
			(end 0.504 0.248)
			(stroke
				(width 0.15)
				(type solid)
			)
			(layer "F.Fab")
		)
		(fp_line
			(start -0.494 -0.25)
			(end 0.504 -0.25)
			(stroke
				(width 0.15)
				(type solid)
			)
			(layer "F.Fab")
		)
		(fp_line
			(start 0.504 0.248)
			(end -0.494 0.248)
			(stroke
				(width 0.15)
				(type solid)
			)
			(layer "F.Fab")
		)
		(fp_line
			(start -0.494 0.248)
			(end -0.494 -0.25)
			(stroke
				(width 0.15)
				(type solid)
			)
			(layer "F.Fab")
		)
		(fp_text user "${REFERENCE}"
			(at -0.939 4.599 90)
			(layer "F.Fab")
			(effects
				(font
					(size 0.7 0.7)
					(thickness 0.15)
				)
				(justify left bottom)
			)
		)
		(fp_text user "License: Apache-2.0"
			(at -0.939 5.799 90)
			(layer "F.Fab")
			(effects
				(font
					(size 0.7 0.7)
					(thickness 0.15)
				)
				(justify left bottom)
			)
		)
		(fp_text user "Author: Antmicro"
			(at -0.939 3.399 90)
			(layer "F.Fab")
			(effects
				(font
					(size 0.7 0.7)
					(thickness 0.15)
				)
				(justify left bottom)
			)
		)
		(pad "1" smd roundrect
			(at -0.48 0 90)
			(size 0.59 0.64)
			(layers "F.Cu" "F.Mask" "F.Paste")
			(roundrect_rratio 0.25)
			(net 34 "/Debug FTDI + VNA/FTDI_VCORE")
			(pintype "passive")
		)
		(pad "2" smd roundrect
			(at 0.48 0 90)
			(size 0.59 0.64)
			(layers "F.Cu" "F.Mask" "F.Paste")
			(roundrect_rratio 0.25)
			(net 1 "GND")
			(pintype "passive")
		)
	)
	(footprint "antmicro-footprints:C_0402_1005Metric"
		(layer "F.Cu")
		(at 148.592843 162.216328)
		(descr "Capacitor SMD 0402")
		(tags "capacitor SMD 0402")
		(property "Reference" "C120"
			(at 0.887157 0.393672 0)
			(layer "F.SilkS")
			(effects
				(font
					(size 0.7 0.7)
					(thickness 0.15)
				)
				(justify left bottom)
			)
		)
		(property "Value" "C_100n_0402"
			(at -1.022927 2.155213 0)
			(layer "F.Fab")
			(effects
				(font
					(size 0.7 0.7)
					(thickness 0.15)
				)
				(justify left bottom)
			)
		)
		(property "Datasheet" "https://www.murata.com/products/productdetail?partno=GRM155R61H104KE14%23"
			(at 0 0 0)
			(layer "F.Fab")
			(hide yes)
			(effects
				(font
					(size 1.27 1.27)
					(thickness 0.15)
				)
			)
		)
		(property "Manufacturer" "Murata"
			(at 0 0 0)
			(unlocked yes)
			(layer "F.Fab")
			(hide yes)
			(effects
				(font
					(size 1 1)
					(thickness 0.15)
				)
			)
		)
		(property "MPN" "GRM155R61H104KE14D"
			(at 0 0 0)
			(unlocked yes)
			(layer "F.Fab")
			(hide yes)
			(effects
				(font
					(size 1 1)
					(thickness 0.15)
				)
			)
		)
		(property "Val" "100n"
			(at 0 0 0)
			(unlocked yes)
			(layer "F.Fab")
			(hide yes)
			(effects
				(font
					(size 1 1)
					(thickness 0.15)
				)
			)
		)
		(property "License" "Apache-2.0"
			(at 0 0 0)
			(unlocked yes)
			(layer "F.Fab")
			(hide yes)
			(effects
				(font
					(size 1 1)
					(thickness 0.15)
				)
			)
		)
		(property "Author" "Antmicro"
			(at 0 0 0)
			(unlocked yes)
			(layer "F.Fab")
			(hide yes)
			(effects
				(font
					(size 1 1)
					(thickness 0.15)
				)
			)
		)
		(property "Voltage" "50V"
			(at 0 0 0)
			(unlocked yes)
			(layer "F.Fab")
			(hide yes)
			(effects
				(font
					(size 1 1)
					(thickness 0.15)
				)
			)
		)
		(property "Dielectric" "X5R"
			(at 0 0 0)
			(unlocked yes)
			(layer "F.Fab")
			(hide yes)
			(effects
				(font
					(size 1 1)
					(thickness 0.15)
				)
			)
		)
		(sheetname "/Debug FTDI + VNA/")
		(sheetfile "debug-ftdi.kicad_sch")
		(attr smd)
		(fp_rect
			(start -0.925 -0.47)
			(end 0.925 0.47)
			(stroke
				(width 0.05)
				(type default)
			)
			(fill no)
			(layer "F.CrtYd")
		)
		(fp_line
			(start -0.494 -0.25)
			(end 0.504 -0.25)
			(stroke
				(width 0.15)
				(type solid)
			)
			(layer "F.Fab")
		)
		(fp_line
			(start -0.494 0.248)
			(end -0.494 -0.25)
			(stroke
				(width 0.15)
				(type solid)
			)
			(layer "F.Fab")
		)
		(fp_line
			(start 0.504 -0.25)
			(end 0.504 0.248)
			(stroke
				(width 0.15)
				(type solid)
			)
			(layer "F.Fab")
		)
		(fp_line
			(start 0.504 0.248)
			(end -0.494 0.248)
			(stroke
				(width 0.15)
				(type solid)
			)
			(layer "F.Fab")
		)
		(fp_text user "License: Apache-2.0"
			(at -0.939 5.799 0)
			(layer "F.Fab")
			(effects
				(font
					(size 0.7 0.7)
					(thickness 0.15)
				)
				(justify left bottom)
			)
		)
		(fp_text user "${REFERENCE}"
			(at -0.939 4.599 0)
			(layer "F.Fab")
			(effects
				(font
					(size 0.7 0.7)
					(thickness 0.15)
				)
				(justify left bottom)
			)
		)
		(fp_text user "Author: Antmicro"
			(at -0.939 3.399 0)
			(layer "F.Fab")
			(effects
				(font
					(size 0.7 0.7)
					(thickness 0.15)
				)
				(justify left bottom)
			)
		)
		(pad "1" smd roundrect
			(at -0.48 0)
			(size 0.59 0.64)
			(layers "F.Cu" "F.Mask" "F.Paste")
			(roundrect_rratio 0.25)
			(net 6 "/Debug FTDI + VNA/FTDI_3V3")
			(pintype "passive")
		)
		(pad "2" smd roundrect
			(at 0.48 0)
			(size 0.59 0.64)
			(layers "F.Cu" "F.Mask" "F.Paste")
			(roundrect_rratio 0.25)
			(net 1 "GND")
			(pintype "passive")
		)
	)
)
